# BASEBOARD_FAB2 (Tioga Pass) — schematic netlist excerpt (pin names and nets, part order shuffled) for the footprints in the layout excerpt that follows; sources: Cadence DE-HDL packaged netlist, KiCad conversion of Wiwynn_Tioga_Pass_MB.brd

U9A3  TC7PZ14FU-GP  pkg DISCRET-GA1  page 175
  \1a\  = FP_RST_BTN_R_N
  GND  = GND
  \2a\  = FP_RST_BTN_BUF1_N
  \2y\  = RST_SYSTEM_BTN_BUF_N
  VCC  = P3V3_STBY
  \1y\  = FP_RST_BTN_BUF1_N

C2D8  CAP  10UF 4V 20% X6S  pkg 0603LF  page 76 : A = PVSA_CPU1 ; B = GND
C8E8  CAP_A  0.1UF 16V 10% X7R  pkg 0402V  page 136 : A = P3V3_STBY ; B = GND

(kicad_pcb
	(version 20260206)
	(generator "pcbnew")
	(generator_version "10.0")
	(general
		(thickness 1.6)
		(legacy_teardrops no)
	)
	(paper "A4")
	(title_block
		(title "Wiwynn_Tioga_Pass_MB.brd")
		(comment 1 "Tioga Pass / footprints 1537-1539 of 4770")
	)
	(layers
		(0 "F.Cu" signal "TOP")
		(4 "In1.Cu" signal "L2GND")
		(6 "In2.Cu" signal "L3")
		(8 "In3.Cu" signal "L4GND")
		(10 "In4.Cu" signal "L5")
		(12 "In5.Cu" signal "L6GND")
		(14 "In6.Cu" signal "L7VCC")
		(16 "In7.Cu" signal "L8VCC")
		(18 "In8.Cu" signal "L9GND")
		(20 "In9.Cu" signal "L10")
		(22 "In10.Cu" signal "L11GND")
		(24 "In11.Cu" signal "L12")
		(26 "In12.Cu" signal "L13GND")
		(2 "B.Cu" signal "BOTTOM")
		(9 "F.Adhes" user "F.Adhesive")
		(11 "B.Adhes" user "B.Adhesive")
		(13 "F.Paste" user "Package Geometry/Pastemask Top")
		(15 "B.Paste" user "Package Geometry/Pastemask Bottom")
		(5 "F.SilkS" user "Ref Des/Silkscreen Top")
		(7 "B.SilkS" user "Ref Des/Silkscreen Bottom")
		(1 "F.Mask" user "Board Geometry/Soldermask Top")
		(3 "B.Mask" user "Board Geometry/Soldermask Bottom")
		(17 "Dwgs.User" user "User.Drawings")
		(19 "Cmts.User" user "User.Comments")
		(21 "Eco1.User" user "User.Eco1")
		(23 "Eco2.User" user "User.Eco2")
		(25 "Edge.Cuts" user "Board Geometry/Outline")
		(27 "Margin" user)
		(31 "F.CrtYd" user "Package Geometry/Place Bound Top")
		(29 "B.CrtYd" user "Package Geometry/Place Bound Bottom")
		(35 "F.Fab" user "Ref Des/Assembly Top")
		(33 "B.Fab" user "Ref Des/Assembly Bottom")
	)
	(footprint ""
		(layer "F.Cu")
		(at 417.83 -56.2229)
		(property "Reference" "C8E8"
			(at 0 0 0)
			(layer "F.SilkS")
			(hide yes)
			(effects
				(font
					(size 1.27 1.27)
				)
			)
		)
		(property "Value" ""
			(at 0 0 0)
			(layer "F.Fab")
			(effects
				(font
					(size 1.27 1.27)
				)
			)
		)
		(duplicate_pad_numbers_are_jumpers no)
		(fp_poly
			(pts
				(xy 0.3048 -0.1016) (xy 0.3048 0.9906) (xy -0.3048 0.9906) (xy -0.3048 -0.1016)
			)
			(stroke
				(width 0)
				(type default)
			)
			(fill no)
			(layer "F.CrtYd")
		)
		(fp_line
			(start -0.3048 -0.1016)
			(end -0.3048 0.9906)
			(stroke
				(width 0.1)
				(type default)
			)
			(layer "F.Fab")
		)
		(fp_line
			(start -0.3048 0.9906)
			(end 0.3048 0.9906)
			(stroke
				(width 0.1)
				(type default)
			)
			(layer "F.Fab")
		)
		(fp_line
			(start 0.3048 -0.1016)
			(end -0.3048 -0.1016)
			(stroke
				(width 0.1)
				(type default)
			)
			(layer "F.Fab")
		)
		(fp_line
			(start 0.3048 0.9906)
			(end 0.3048 -0.1016)
			(stroke
				(width 0.1)
				(type default)
			)
			(layer "F.Fab")
		)
		(pad "1" smd rect
			(at 0 0)
			(size 0.508 0.508)
			(layers "F.Cu" "F.Mask" "F.Paste")
			(net "P3V3_STBY")
		)
		(pad "2" smd rect
			(at 0 0.889)
			(size 0.508 0.508)
			(layers "F.Cu" "F.Mask" "F.Paste")
			(net "GND")
		)
		(zone
			(layer "F.Cu")
			(hatch none 0.5)
			(connect_pads
				(clearance 0)
			)
			(min_thickness 0.25)
			(keepout
				(tracks allowed)
				(vias not_allowed)
				(pads allowed)
				(copperpour not_allowed)
				(footprints allowed)
			)
			(placement
				(enabled no)
				(sheetname "")
			)
			(fill
				(thermal_gap 0.5)
				(thermal_bridge_width 0.5)
				(island_removal_mode 0)
			)
			(polygon
				(pts
					(xy 417.576 -55.9689) (xy 418.084 -55.9689) (xy 418.084 -55.5879) (xy 417.576 -55.5879)
				)
			)
		)
		(zone
			(layer "F.Cu")
			(hatch none 0.5)
			(connect_pads
				(clearance 0)
			)
			(min_thickness 0.25)
			(keepout
				(tracks not_allowed)
				(vias allowed)
				(pads allowed)
				(copperpour not_allowed)
				(footprints allowed)
			)
			(placement
				(enabled no)
				(sheetname "")
			)
			(fill
				(thermal_gap 0.5)
				(thermal_bridge_width 0.5)
				(island_removal_mode 0)
			)
			(polygon
				(pts
					(xy 417.576 -55.5879) (xy 418.084 -55.5879) (xy 418.084 -55.9689) (xy 417.576 -55.9689)
				)
			)
		)
	)
	(footprint ""
		(layer "F.Cu")
		(at 479.806 -145.288)
		(property "Reference" "U9A3"
			(at 0 0 0)
			(layer "F.SilkS")
			(hide yes)
			(effects
				(font
					(size 1.27 1.27)
				)
			)
		)
		(property "Value" "*"
			(at -2.3622 -8.3185 0)
			(unlocked yes)
			(layer "F.Fab")
			(hide yes)
			(effects
				(font
					(size 1.27 1.016)
					(thickness 0.1524)
				)
			)
		)
		(property "Device Type" "TC7PZ14FU-GP_DISCRET-GA1-TC7PZA"
			(at -2.3622 -10.2235 0)
			(unlocked yes)
			(layer "F.Fab")
			(hide yes)
			(effects
				(font
					(size 1.27 1.016)
					(thickness 0.1524)
				)
			)
		)
		(duplicate_pad_numbers_are_jumpers no)
		(fp_line
			(start -1.5494 1.7907)
			(end -1.5494 0.8255)
			(stroke
				(width 0.3302)
				(type default)
			)
			(layer "F.SilkS")
		)
		(fp_line
			(start -1.4478 -1.7018)
			(end -1.4478 1.7018)
			(stroke
				(width 0.1524)
				(type default)
			)
			(layer "F.SilkS")
		)
		(fp_line
			(start -1.4478 1.7018)
			(end 1.4478 1.7018)
			(stroke
				(width 0.1524)
				(type default)
			)
			(layer "F.SilkS")
		)
		(fp_line
			(start -0.5715 1.7907)
			(end -1.5494 1.7907)
			(stroke
				(width 0.3302)
				(type default)
			)
			(layer "F.SilkS")
		)
		(fp_line
			(start 1.4478 -1.7018)
			(end -1.4478 -1.7018)
			(stroke
				(width 0.1524)
				(type default)
			)
			(layer "F.SilkS")
		)
		(fp_line
			(start 1.4478 1.7018)
			(end 1.4478 -1.7018)
			(stroke
				(width 0.1524)
				(type default)
			)
			(layer "F.SilkS")
		)
		(fp_poly
			(pts
				(xy -0.6604 1.7272) (xy -1.016 2.0828) (xy -0.3048 2.0828)
			)
			(stroke
				(width 0)
				(type default)
			)
			(fill yes)
			(layer "F.SilkS")
		)
		(fp_poly
			(pts
				(xy -1.524 -1.778) (xy 1.524 -1.778) (xy 1.524 1.778) (xy -1.524 1.778)
			)
			(stroke
				(width 0)
				(type default)
			)
			(fill no)
			(layer "F.CrtYd")
		)
		(fp_poly
			(pts
				(xy -1.524 -1.778) (xy 1.524 -1.778) (xy 1.524 1.778) (xy -1.524 1.778)
			)
			(stroke
				(width 0)
				(type default)
			)
			(fill no)
			(layer "F.Fab")
		)
		(pad "1" smd rect
			(at -0.65024 0.9398)
			(size 0.4064 1.016)
			(layers "F.Cu" "F.Mask" "F.Paste")
			(net "FP_RST_BTN_R_N")
		)
		(pad "2" smd rect
			(at 0 0.9398)
			(size 0.4064 1.016)
			(layers "F.Cu" "F.Mask" "F.Paste")
			(net "GND")
		)
		(pad "3" smd rect
			(at 0.65024 0.9398)
			(size 0.4064 1.016)
			(layers "F.Cu" "F.Mask" "F.Paste")
			(net "FP_RST_BTN_BUF1_N")
		)
		(pad "4" smd rect
			(at 0.65024 -0.9398)
			(size 0.4064 1.016)
			(layers "F.Cu" "F.Mask" "F.Paste")
			(net "RST_SYSTEM_BTN_BUF_N")
		)
		(pad "5" smd rect
			(at 0 -0.9398)
			(size 0.4064 1.016)
			(layers "F.Cu" "F.Mask" "F.Paste")
			(net "P3V3_STBY")
		)
		(pad "6" smd rect
			(at -0.65024 -0.9398)
			(size 0.4064 1.016)
			(layers "F.Cu" "F.Mask" "F.Paste")
			(net "FP_RST_BTN_BUF1_N")
		)
	)
	(footprint ""
		(layer "F.Cu")
		(at 97.132902 -83.84159)
		(property "Reference" "C2D8"
			(at 0 0 0)
			(layer "F.SilkS")
			(hide yes)
			(effects
				(font
					(size 1.27 1.27)
				)
			)
		)
		(property "Value" ""
			(at 0 0 0)
			(layer "F.Fab")
			(effects
				(font
					(size 1.27 1.27)
				)
			)
		)
		(duplicate_pad_numbers_are_jumpers no)
		(fp_poly
			(pts
				(xy -0.4953 -0.2032) (xy 0.4953 -0.2032) (xy 0.4953 1.6002) (xy -0.4953 1.6002)
			)
			(stroke
				(width 0)
				(type default)
			)
			(fill no)
			(layer "F.CrtYd")
		)
		(fp_line
			(start -0.4953 -0.2032)
			(end 0.4953 -0.2032)
			(stroke
				(width 0.1)
				(type default)
			)
			(layer "F.Fab")
		)
		(fp_line
			(start -0.4953 1.6002)
			(end -0.4953 -0.2032)
			(stroke
				(width 0.1)
				(type default)
			)
			(layer "F.Fab")
		)
		(fp_line
			(start 0.4953 -0.2032)
			(end 0.4953 1.6002)
			(stroke
				(width 0.1)
				(type default)
			)
			(layer "F.Fab")
		)
		(fp_line
			(start 0.4953 1.6002)
			(end -0.4953 1.6002)
			(stroke
				(width 0.1)
				(type default)
			)
			(layer "F.Fab")
		)
		(pad "1" smd rect
			(at 0 0)
			(size 0.762 0.889)
			(layers "F.Cu" "F.Mask" "F.Paste")
			(net "PVSA_CPU1")
		)
		(pad "2" smd rect
			(at 0 1.397)
			(size 0.762 0.889)
			(layers "F.Cu" "F.Mask" "F.Paste")
			(net "GND")
		)
		(zone
			(layer "F.Cu")
			(hatch none 0.5)
			(connect_pads
				(clearance 0)
			)
			(min_thickness 0.25)
			(keepout
				(tracks not_allowed)
				(vias allowed)
				(pads allowed)
				(copperpour not_allowed)
				(footprints allowed)
			)
			(placement
				(enabled no)
				(sheetname "")
			)
			(fill
				(thermal_gap 0.5)
				(thermal_bridge_width 0.5)
				(island_removal_mode 0)
			)
			(polygon
				(pts
					(xy 96.751902 -83.39709) (xy 97.513902 -83.39709) (xy 97.513902 -82.88909) (xy 96.751902 -82.88909)
				)
			)
		)
	)
)
